(kicad_pcb
	(version 20260206)
	(generator "pcbnew")
	(generator_version "10.0")
	(general
		(thickness 1.6)
		(legacy_teardrops no)
	)
	(paper "A4")
	(title_block
		(title "baseboard — 13948-1b.1110WZS1818.brd")
		(comment 1 "Honey Badger (Wiwynn) / footprints 2470-2477 of 2523")
	)
	(layers
		(0 "F.Cu" signal "TOP")
		(4 "In1.Cu" signal "L2GND")
		(6 "In2.Cu" signal "L3")
		(8 "In3.Cu" signal "L4VCC")
		(10 "In4.Cu" signal "L5VCC")
		(12 "In5.Cu" signal "L6")
		(14 "In6.Cu" signal "L7GND")
		(2 "B.Cu" signal "BOTTOM")
		(9 "F.Adhes" user "F.Adhesive")
		(11 "B.Adhes" user "B.Adhesive")
		(13 "F.Paste" user "Package Geometry/Pastemask Top")
		(15 "B.Paste" user "Package Geometry/Pastemask Bottom")
		(5 "F.SilkS" user "Ref Des/Silkscreen Top")
		(7 "B.SilkS" user "Ref Des/Silkscreen Bottom")
		(1 "F.Mask" user "Board Geometry/Soldermask Top")
		(3 "B.Mask" user "Board Geometry/Soldermask Bottom")
		(17 "Dwgs.User" user "User.Drawings")
		(19 "Cmts.User" user "User.Comments")
		(21 "Eco1.User" user "User.Eco1")
		(23 "Eco2.User" user "User.Eco2")
		(25 "Edge.Cuts" user "Board Geometry/Outline")
		(27 "Margin" user)
		(31 "F.CrtYd" user "Package Geometry/Place Bound Top")
		(29 "B.CrtYd" user "Package Geometry/Place Bound Bottom")
		(35 "F.Fab" user "Ref Des/Assembly Top")
		(33 "B.Fab" user "Ref Des/Assembly Bottom")
	)
	(footprint ""
		(layer "B.Cu")
		(at 127.11557 -89.281 90)
		(property "Reference" "SC1174"
			(at 0 0 90)
			(layer "B.SilkS")
			(hide yes)
			(effects
				(font
					(size 1.27 1.27)
				)
				(justify mirror)
			)
		)
		(property "Value" "SCD1U16V2KX-3GP"
			(at -1.1811 -2.7051 90)
			(unlocked yes)
			(layer "B.Fab")
			(hide yes)
			(effects
				(font
					(size 1.016 1.016)
					(thickness 0.1524)
				)
				(justify mirror)
			)
		)
		(property "Device Type" "C402H22"
			(at -1.1811 -4.2291 90)
			(unlocked yes)
			(layer "B.Fab")
			(hide yes)
			(effects
				(font
					(size 1.016 1.016)
					(thickness 0.1524)
				)
				(justify mirror)
			)
		)
		(duplicate_pad_numbers_are_jumpers no)
		(fp_rect
			(start 0.4318 0.9525)
			(end -0.4318 -0.9525)
			(stroke
				(width 0)
				(type default)
			)
			(fill no)
			(layer "B.CrtYd")
		)
		(fp_rect
			(start 0.4318 0.9525)
			(end -0.4318 -0.9525)
			(stroke
				(width 0)
				(type default)
			)
			(fill no)
			(layer "B.Fab")
		)
		(pad "1" smd custom
			(at 0 -0.4445 270)
			(size 0.1524 0.1524)
			(layers "B.Cu" "B.Mask" "B.Paste")
			(net "GB_VDDA")
			(options
				(clearance outline)
				(anchor circle)
			)
			(primitives
				(gr_poly
					(pts
						(arc
							(start 0.3048 0.2032)
							(mid 0.275042 0.275042)
							(end 0.2032 0.3048)
						)
						(arc
							(start -0.2032 0.3048)
							(mid -0.275042 0.275042)
							(end -0.3048 0.2032)
						)
						(arc
							(start -0.3048 -0.2032)
							(mid -0.275042 -0.275042)
							(end -0.2032 -0.3048)
						)
						(arc
							(start 0.2032 -0.3048)
							(mid 0.275042 -0.275042)
							(end 0.3048 -0.2032)
						)
					)
					(width 0)
					(fill yes)
				)
			)
		)
		(pad "2" smd custom
			(at 0 0.4445 270)
			(size 0.1524 0.1524)
			(layers "B.Cu" "B.Mask" "B.Paste")
			(net "GND")
			(options
				(clearance outline)
				(anchor circle)
			)
			(primitives
				(gr_poly
					(pts
						(arc
							(start 0.3048 0.2032)
							(mid 0.275042 0.275042)
							(end 0.2032 0.3048)
						)
						(arc
							(start -0.2032 0.3048)
							(mid -0.275042 0.275042)
							(end -0.3048 0.2032)
						)
						(arc
							(start -0.3048 -0.2032)
							(mid -0.275042 -0.275042)
							(end -0.2032 -0.3048)
						)
						(arc
							(start 0.2032 -0.3048)
							(mid 0.275042 -0.275042)
							(end 0.3048 -0.2032)
						)
					)
					(width 0)
					(fill yes)
				)
			)
		)
	)
	(footprint ""
		(layer "B.Cu")
		(at 115.628166 -41.26484)
		(property "Reference" "STP1"
			(at 0 0 0)
			(layer "B.SilkS")
			(hide yes)
			(effects
				(font
					(size 1.27 1.27)
				)
				(justify mirror)
			)
		)
		(property "Value" "TPAD28"
			(at -0.0127 -1.8034 0)
			(unlocked yes)
			(layer "B.Fab")
			(hide yes)
			(effects
				(font
					(size 1.016 1.016)
					(thickness 0.1524)
				)
				(justify mirror)
			)
		)
		(property "Device Type" "TPAD28"
			(at -0.0127 -3.3274 0)
			(unlocked yes)
			(layer "B.Fab")
			(hide yes)
			(effects
				(font
					(size 1.016 1.016)
					(thickness 0.1524)
				)
				(justify mirror)
			)
		)
		(duplicate_pad_numbers_are_jumpers no)
		(fp_poly
			(pts
				(arc
					(start 0.3556 0)
					(mid -0.3556 0)
					(end 0.3556 0)
				)
			)
			(stroke
				(width 0)
				(type default)
			)
			(fill no)
			(layer "B.CrtYd")
		)
		(fp_poly
			(pts
				(arc
					(start 0.6096 0)
					(mid -0.6096 0)
					(end 0.6096 0)
				)
			)
			(stroke
				(width 0)
				(type default)
			)
			(fill no)
			(layer "B.Fab")
		)
		(pad "1" smd circle
			(at 0 0 180)
			(size 0.7112 0.7112)
			(layers "B.Cu" "B.Mask" "B.Paste")
			(net "IOC_GPIO_24")
		)
	)
	(footprint ""
		(layer "B.Cu")
		(at 110.713266 -40.28948 -90)
		(property "Reference" "SC987"
			(at 0 0 90)
			(layer "B.SilkS")
			(hide yes)
			(effects
				(font
					(size 1.27 1.27)
				)
				(justify mirror)
			)
		)
		(property "Value" "SCD1U16V2KX-3GP"
			(at -1.1811 -2.7051 270)
			(unlocked yes)
			(layer "B.Fab")
			(hide yes)
			(effects
				(font
					(size 1.016 1.016)
					(thickness 0.1524)
				)
				(justify mirror)
			)
		)
		(property "Device Type" "C402H22"
			(at -1.1811 -4.2291 270)
			(unlocked yes)
			(layer "B.Fab")
			(hide yes)
			(effects
				(font
					(size 1.016 1.016)
					(thickness 0.1524)
				)
				(justify mirror)
			)
		)
		(duplicate_pad_numbers_are_jumpers no)
		(fp_rect
			(start 0.4318 0.9525)
			(end -0.4318 -0.9525)
			(stroke
				(width 0)
				(type default)
			)
			(fill no)
			(layer "B.CrtYd")
		)
		(fp_rect
			(start 0.4318 0.9525)
			(end -0.4318 -0.9525)
			(stroke
				(width 0)
				(type default)
			)
			(fill no)
			(layer "B.Fab")
		)
		(pad "1" smd custom
			(at 0 -0.4445 90)
			(size 0.1524 0.1524)
			(layers "B.Cu" "B.Mask" "B.Paste")
			(net "P1V8_C")
			(options
				(clearance outline)
				(anchor circle)
			)
			(primitives
				(gr_poly
					(pts
						(arc
							(start 0.3048 0.2032)
							(mid 0.275042 0.275042)
							(end 0.2032 0.3048)
						)
						(arc
							(start -0.2032 0.3048)
							(mid -0.275042 0.275042)
							(end -0.3048 0.2032)
						)
						(arc
							(start -0.3048 -0.2032)
							(mid -0.275042 -0.275042)
							(end -0.2032 -0.3048)
						)
						(arc
							(start 0.2032 -0.3048)
							(mid 0.275042 -0.275042)
							(end 0.3048 -0.2032)
						)
					)
					(width 0)
					(fill yes)
				)
			)
		)
		(pad "2" smd custom
			(at 0 0.4445 90)
			(size 0.1524 0.1524)
			(layers "B.Cu" "B.Mask" "B.Paste")
			(net "GND")
			(options
				(clearance outline)
				(anchor circle)
			)
			(primitives
				(gr_poly
					(pts
						(arc
							(start 0.3048 0.2032)
							(mid 0.275042 0.275042)
							(end 0.2032 0.3048)
						)
						(arc
							(start -0.2032 0.3048)
							(mid -0.275042 0.275042)
							(end -0.3048 0.2032)
						)
						(arc
							(start -0.3048 -0.2032)
							(mid -0.275042 -0.275042)
							(end -0.2032 -0.3048)
						)
						(arc
							(start 0.2032 -0.3048)
							(mid 0.275042 -0.275042)
							(end 0.3048 -0.2032)
						)
					)
					(width 0)
					(fill yes)
				)
			)
		)
	)
	(footprint ""
		(layer "B.Cu")
		(at 100.21697 -109.982 180)
		(property "Reference" "SR748"
			(at 0 0 0)
			(layer "B.SilkS")
			(hide yes)
			(effects
				(font
					(size 1.27 1.27)
				)
				(justify mirror)
			)
		)
		(property "Value" "4K7R2F-GP"
			(at -0.064008 -3.993896 180)
			(unlocked yes)
			(layer "B.Fab")
			(hide yes)
			(effects
				(font
					(size 1.016 1.016)
					(thickness 0.1524)
				)
				(justify mirror)
			)
		)
		(property "Device Type" "R402H16"
			(at -0.064008 -5.517896 180)
			(unlocked yes)
			(layer "B.Fab")
			(hide yes)
			(effects
				(font
					(size 1.016 1.016)
					(thickness 0.1524)
				)
				(justify mirror)
			)
		)
		(duplicate_pad_numbers_are_jumpers no)
		(fp_line
			(start 0.508 -0.9398)
			(end 0.508 0.9398)
			(stroke
				(width 0.1524)
				(type default)
			)
			(layer "B.SilkS")
		)
		(fp_line
			(start -0.508 -0.9398)
			(end 0.508 -0.9398)
			(stroke
				(width 0.1524)
				(type default)
			)
			(layer "B.SilkS")
		)
		(fp_rect
			(start 0.508 0.9398)
			(end -0.508 -0.9398)
			(stroke
				(width 0)
				(type default)
			)
			(fill no)
			(layer "B.CrtYd")
		)
		(fp_rect
			(start 0.508 0.9398)
			(end -0.508 -0.9398)
			(stroke
				(width 0)
				(type default)
			)
			(fill no)
			(layer "B.Fab")
		)
		(pad "1" smd custom
			(at 0 -0.4445)
			(size 0.1397 0.1397)
			(layers "B.Cu" "B.Mask" "B.Paste")
			(net "SIO_D_OUT")
			(options
				(clearance outline)
				(anchor circle)
			)
			(primitives
				(gr_poly
					(pts
						(arc
							(start -0.1778 0.2794)
							(mid -0.249642 0.249642)
							(end -0.2794 0.1778)
						)
						(arc
							(start -0.2794 -0.1778)
							(mid -0.249642 -0.249642)
							(end -0.1778 -0.2794)
						)
						(arc
							(start 0.1778 -0.2794)
							(mid 0.249642 -0.249642)
							(end 0.2794 -0.1778)
						)
						(arc
							(start 0.2794 0.1778)
							(mid 0.249642 0.249642)
							(end 0.1778 0.2794)
						)
					)
					(width 0)
					(fill yes)
				)
			)
		)
		(pad "2" smd custom
			(at 0 0.4445)
			(size 0.1397 0.1397)
			(layers "B.Cu" "B.Mask" "B.Paste")
			(net "P1V8_E")
			(options
				(clearance outline)
				(anchor circle)
			)
			(primitives
				(gr_poly
					(pts
						(arc
							(start -0.1778 0.2794)
							(mid -0.249642 0.249642)
							(end -0.2794 0.1778)
						)
						(arc
							(start -0.2794 -0.1778)
							(mid -0.249642 -0.249642)
							(end -0.1778 -0.2794)
						)
						(arc
							(start 0.1778 -0.2794)
							(mid 0.249642 -0.249642)
							(end 0.2794 -0.1778)
						)
						(arc
							(start 0.2794 0.1778)
							(mid 0.249642 0.249642)
							(end 0.1778 0.2794)
						)
					)
					(width 0)
					(fill yes)
				)
			)
		)
	)
	(footprint ""
		(layer "B.Cu")
		(at 103.13416 -31.623)
		(property "Reference" "SC874"
			(at 0 0 0)
			(layer "B.SilkS")
			(hide yes)
			(effects
				(font
					(size 1.27 1.27)
				)
				(justify mirror)
			)
		)
		(property "Value" "SCD22U6D3V1MX-1-GP"
			(at 2.8321 -1.7399 0)
			(unlocked yes)
			(layer "B.Fab")
			(hide yes)
			(effects
				(font
					(size 1.016 1.016)
					(thickness 0.1524)
				)
				(justify mirror)
			)
		)
		(property "Device Type" "C0201H13"
			(at 2.8321 -3.2639 0)
			(unlocked yes)
			(layer "B.Fab")
			(hide yes)
			(effects
				(font
					(size 1.016 1.016)
					(thickness 0.1524)
				)
				(justify mirror)
			)
		)
		(duplicate_pad_numbers_are_jumpers no)
		(fp_rect
			(start 0.2794 0.6477)
			(end -0.2794 -0.6477)
			(stroke
				(width 0)
				(type default)
			)
			(fill no)
			(layer "B.CrtYd")
		)
		(fp_rect
			(start 0.2794 0.6477)
			(end -0.2794 -0.6477)
			(stroke
				(width 0)
				(type default)
			)
			(fill no)
			(layer "B.Fab")
		)
		(pad "1" smd custom
			(at 0 -0.2794 180)
			(size 0.0762 0.0762)
			(layers "B.Cu" "B.Mask" "B.Paste")
			(net "PCIE_SAS_C_CPU_RX_N6")
			(options
				(clearance outline)
				(anchor circle)
			)
			(primitives
				(gr_poly
					(pts
						(arc
							(start 0.1524 0.127)
							(mid 0.137521 0.162921)
							(end 0.1016 0.1778)
						)
						(arc
							(start -0.1016 0.1778)
							(mid -0.137521 0.162921)
							(end -0.1524 0.127)
						)
						(arc
							(start -0.1524 -0.127)
							(mid -0.137521 -0.162921)
							(end -0.1016 -0.1778)
						)
						(arc
							(start 0.1016 -0.1778)
							(mid 0.137521 -0.162921)
							(end 0.1524 -0.127)
						)
					)
					(width 0)
					(fill yes)
				)
			)
		)
		(pad "2" smd custom
			(at 0 0.2794 180)
			(size 0.0762 0.0762)
			(layers "B.Cu" "B.Mask" "B.Paste")
			(net "PCIE_SAS_CPU_RX_N6")
			(options
				(clearance outline)
				(anchor circle)
			)
			(primitives
				(gr_poly
					(pts
						(arc
							(start 0.1524 0.127)
							(mid 0.137521 0.162921)
							(end 0.1016 0.1778)
						)
						(arc
							(start -0.1016 0.1778)
							(mid -0.137521 0.162921)
							(end -0.1524 0.127)
						)
						(arc
							(start -0.1524 -0.127)
							(mid -0.137521 -0.162921)
							(end -0.1016 -0.1778)
						)
						(arc
							(start 0.1016 -0.1778)
							(mid 0.137521 -0.162921)
							(end 0.1524 -0.127)
						)
					)
					(width 0)
					(fill yes)
				)
			)
		)
	)
	(footprint ""
		(layer "B.Cu")
		(at 108.839 -62.23 -90)
		(property "Reference" "PR191"
			(at 0 0 90)
			(layer "B.SilkS")
			(hide yes)
			(effects
				(font
					(size 1.27 1.27)
				)
				(justify mirror)
			)
		)
		(property "Value" "221R2F-2-GP"
			(at -0.064008 -3.993896 270)
			(unlocked yes)
			(layer "B.Fab")
			(hide yes)
			(effects
				(font
					(size 1.016 1.016)
					(thickness 0.1524)
				)
				(justify mirror)
			)
		)
		(property "Device Type" "R402H16"
			(at -0.064008 -5.517896 270)
			(unlocked yes)
			(layer "B.Fab")
			(hide yes)
			(effects
				(font
					(size 1.016 1.016)
					(thickness 0.1524)
				)
				(justify mirror)
			)
		)
		(duplicate_pad_numbers_are_jumpers no)
		(fp_line
			(start -0.508 -0.9398)
			(end 0.508 -0.9398)
			(stroke
				(width 0.1524)
				(type default)
			)
			(layer "B.SilkS")
		)
		(fp_line
			(start 0.508 -0.9398)
			(end 0.508 0.9398)
			(stroke
				(width 0.1524)
				(type default)
			)
			(layer "B.SilkS")
		)
		(fp_rect
			(start 0.508 0.9398)
			(end -0.508 -0.9398)
			(stroke
				(width 0)
				(type default)
			)
			(fill no)
			(layer "B.CrtYd")
		)
		(fp_rect
			(start 0.508 0.9398)
			(end -0.508 -0.9398)
			(stroke
				(width 0)
				(type default)
			)
			(fill no)
			(layer "B.Fab")
		)
		(pad "1" smd custom
			(at 0 -0.4445 90)
			(size 0.1397 0.1397)
			(layers "B.Cu" "B.Mask" "B.Paste")
			(net "VT235_VDES_RCC")
			(options
				(clearance outline)
				(anchor circle)
			)
			(primitives
				(gr_poly
					(pts
						(arc
							(start -0.1778 0.2794)
							(mid -0.249642 0.249642)
							(end -0.2794 0.1778)
						)
						(arc
							(start -0.2794 -0.1778)
							(mid -0.249642 -0.249642)
							(end -0.1778 -0.2794)
						)
						(arc
							(start 0.1778 -0.2794)
							(mid 0.249642 -0.249642)
							(end 0.2794 -0.1778)
						)
						(arc
							(start 0.2794 0.1778)
							(mid 0.249642 0.249642)
							(end 0.1778 0.2794)
						)
					)
					(width 0)
					(fill yes)
				)
			)
		)
		(pad "2" smd custom
			(at 0 0.4445 90)
			(size 0.1397 0.1397)
			(layers "B.Cu" "B.Mask" "B.Paste")
			(net "GND")
			(options
				(clearance outline)
				(anchor circle)
			)
			(primitives
				(gr_poly
					(pts
						(arc
							(start -0.1778 0.2794)
							(mid -0.249642 0.249642)
							(end -0.2794 0.1778)
						)
						(arc
							(start -0.2794 -0.1778)
							(mid -0.249642 -0.249642)
							(end -0.1778 -0.2794)
						)
						(arc
							(start 0.1778 -0.2794)
							(mid 0.249642 -0.249642)
							(end 0.2794 -0.1778)
						)
						(arc
							(start 0.2794 0.1778)
							(mid 0.249642 0.249642)
							(end 0.1778 0.2794)
						)
					)
					(width 0)
					(fill yes)
				)
			)
		)
	)
	(footprint ""
		(layer "B.Cu")
		(at 89.789 -3.429 180)
		(property "Reference" "PR179"
			(at 0 0 0)
			(layer "B.SilkS")
			(hide yes)
			(effects
				(font
					(size 1.27 1.27)
				)
				(justify mirror)
			)
		)
		(property "Value" "10KR2F-2-GP"
			(at -0.064008 -3.993896 180)
			(unlocked yes)
			(layer "B.Fab")
			(hide yes)
			(effects
				(font
					(size 1.016 1.016)
					(thickness 0.1524)
				)
				(justify mirror)
			)
		)
		(property "Device Type" "R402H16"
			(at -0.064008 -5.517896 180)
			(unlocked yes)
			(layer "B.Fab")
			(hide yes)
			(effects
				(font
					(size 1.016 1.016)
					(thickness 0.1524)
				)
				(justify mirror)
			)
		)
		(duplicate_pad_numbers_are_jumpers no)
		(fp_line
			(start 0.508 -0.9398)
			(end 0.508 0.9398)
			(stroke
				(width 0.1524)
				(type default)
			)
			(layer "B.SilkS")
		)
		(fp_line
			(start -0.508 -0.9398)
			(end 0.508 -0.9398)
			(stroke
				(width 0.1524)
				(type default)
			)
			(layer "B.SilkS")
		)
		(fp_rect
			(start 0.508 0.9398)
			(end -0.508 -0.9398)
			(stroke
				(width 0)
				(type default)
			)
			(fill no)
			(layer "B.CrtYd")
		)
		(fp_rect
			(start 0.508 0.9398)
			(end -0.508 -0.9398)
			(stroke
				(width 0)
				(type default)
			)
			(fill no)
			(layer "B.Fab")
		)
		(pad "1" smd custom
			(at 0 -0.4445)
			(size 0.1397 0.1397)
			(layers "B.Cu" "B.Mask" "B.Paste")
			(net "GND")
			(options
				(clearance outline)
				(anchor circle)
			)
			(primitives
				(gr_poly
					(pts
						(arc
							(start -0.1778 0.2794)
							(mid -0.249642 0.249642)
							(end -0.2794 0.1778)
						)
						(arc
							(start -0.2794 -0.1778)
							(mid -0.249642 -0.249642)
							(end -0.1778 -0.2794)
						)
						(arc
							(start 0.1778 -0.2794)
							(mid 0.249642 -0.249642)
							(end 0.2794 -0.1778)
						)
						(arc
							(start 0.2794 0.1778)
							(mid 0.249642 0.249642)
							(end 0.1778 0.2794)
						)
					)
					(width 0)
					(fill yes)
				)
			)
		)
		(pad "2" smd custom
			(at 0 0.4445)
			(size 0.1397 0.1397)
			(layers "B.Cu" "B.Mask" "B.Paste")
			(net "P0V955_C")
			(options
				(clearance outline)
				(anchor circle)
			)
			(primitives
				(gr_poly
					(pts
						(arc
							(start -0.1778 0.2794)
							(mid -0.249642 0.249642)
							(end -0.2794 0.1778)
						)
						(arc
							(start -0.2794 -0.1778)
							(mid -0.249642 -0.249642)
							(end -0.1778 -0.2794)
						)
						(arc
							(start 0.1778 -0.2794)
							(mid 0.249642 -0.249642)
							(end 0.2794 -0.1778)
						)
						(arc
							(start 0.2794 0.1778)
							(mid 0.249642 0.249642)
							(end 0.1778 0.2794)
						)
					)
					(width 0)
					(fill yes)
				)
			)
		)
	)
	(footprint ""
		(layer "B.Cu")
		(at 107.525566 -36.98748)
		(property "Reference" "STP42"
			(at 0 0 0)
			(layer "B.SilkS")
			(hide yes)
			(effects
				(font
					(size 1.27 1.27)
				)
				(justify mirror)
			)
		)
		(property "Value" "TPAD28"
			(at -0.0127 -1.8034 0)
			(unlocked yes)
			(layer "B.Fab")
			(hide yes)
			(effects
				(font
					(size 1.016 1.016)
					(thickness 0.1524)
				)
				(justify mirror)
			)
		)
		(property "Device Type" "TPAD28"
			(at -0.0127 -3.3274 0)
			(unlocked yes)
			(layer "B.Fab")
			(hide yes)
			(effects
				(font
					(size 1.016 1.016)
					(thickness 0.1524)
				)
				(justify mirror)
			)
		)
		(duplicate_pad_numbers_are_jumpers no)
		(fp_poly
			(pts
				(arc
					(start 0.3556 0)
					(mid -0.3556 0)
					(end 0.3556 0)
				)
			)
			(stroke
				(width 0)
				(type default)
			)
			(fill no)
			(layer "B.CrtYd")
		)
		(fp_poly
			(pts
				(arc
					(start 0.6096 0)
					(mid -0.6096 0)
					(end 0.6096 0)
				)
			)
			(stroke
				(width 0)
				(type default)
			)
			(fill no)
			(layer "B.Fab")
		)
		(pad "1" smd circle
			(at 0 0 180)
			(size 0.7112 0.7112)
			(layers "B.Cu" "B.Mask" "B.Paste")
			(net "SYS_DBMODE0")
		)
	)
)
